# TIMECARD (Time Appliance Project (Time Card)) — schematic netlist excerpt (pin names and nets, part order shuffled) for the footprints in the layout excerpt that follows; sources: Cadence DE-HDL packaged netlist, KiCad conversion of R4006-B0001-02_R01.brd

R153  RESISTOR  4.7KOHM 1%  pkg SMC_0402R_H016  page 16 : \1\ = SG ; \2\ = UNNAMED_5_PCA9546APWTSSOP16_I_1
C207  CAPACITOR  0.1UF 10V 10%  pkg SMC_0402R_H022  page 14 : \1\ = XP1R0V_FPGA_VCCINT ; \2\ = SG

(kicad_pcb
	(version 20260206)
	(generator "pcbnew")
	(generator_version "10.0")
	(general
		(thickness 1.6)
		(legacy_teardrops no)
	)
	(paper "A4")
	(title_block
		(title "timecard-production-celestica-r4006 — R4006-B0001-02_R01.brd")
		(comment 1 "Time Appliance Project (Time Card) / footprints 716-717 of 1113")
	)
	(layers
		(0 "F.Cu" signal "TOP")
		(4 "In1.Cu" signal "L02_GND1")
		(6 "In2.Cu" signal "L03_SIG1")
		(8 "In3.Cu" signal "L04_GND2")
		(10 "In4.Cu" signal "L05_VCC1")
		(12 "In5.Cu" signal "L06_VCC2")
		(14 "In6.Cu" signal "L07_GND3")
		(16 "In7.Cu" signal "L08_SIG2")
		(18 "In8.Cu" signal "L09_GND4")
		(2 "B.Cu" signal "BOTTOM")
		(9 "F.Adhes" user "F.Adhesive")
		(11 "B.Adhes" user "B.Adhesive")
		(13 "F.Paste" user "Package Geometry/Pastemask Top")
		(15 "B.Paste" user "Package Geometry/Pastemask Bottom")
		(5 "F.SilkS" user "Ref Des/Silkscreen Top")
		(7 "B.SilkS" user "Ref Des/Silkscreen Bottom")
		(1 "F.Mask" user "Board Geometry/Soldermask Top")
		(3 "B.Mask" user "Board Geometry/Soldermask Bottom")
		(17 "Dwgs.User" user "User.Drawings")
		(19 "Cmts.User" user "User.Comments")
		(21 "Eco1.User" user "User.Eco1")
		(23 "Eco2.User" user "User.Eco2")
		(25 "Edge.Cuts" user "Board Geometry/Outline")
		(27 "Margin" user)
		(31 "F.CrtYd" user "Package Geometry/Place Bound Top")
		(29 "B.CrtYd" user "Package Geometry/Place Bound Bottom")
		(35 "F.Fab" user "Ref Des/Assembly Top")
		(33 "B.Fab" user "Ref Des/Assembly Bottom")
	)
	(footprint ""
		(layer "B.Cu")
		(at 114.847116 -42.323004 90)
		(property "Reference" "C207"
			(at -1.302004 -41.726866 270)
			(unlocked yes)
			(layer "B.SilkS")
			(effects
				(font
					(size 0.635 0.4064)
					(thickness 0.1524)
				)
				(justify mirror)
			)
		)
		(property "Value" "VAL*"
			(at 0 3.718306 90)
			(unlocked yes)
			(layer "B.Fab")
			(hide yes)
			(effects
				(font
					(size 0.7874 0.5842)
					(thickness 0.127)
				)
				(justify mirror)
			)
		)
		(property "Device Type" "CAPACITOR-G105-0B104-CK,0.1UF,A"
			(at 0 1.432306 90)
			(unlocked yes)
			(layer "B.Fab")
			(hide yes)
			(effects
				(font
					(size 0.7874 0.5842)
					(thickness 0.127)
				)
				(justify mirror)
			)
		)
		(property "User Part Number" "PARTNUM*"
			(at 0 2.575306 90)
			(unlocked yes)
			(layer "Cmts.User")
			(hide yes)
			(effects
				(font
					(size 0.7874 0.5842)
					(thickness 0.127)
				)
				(justify mirror)
			)
		)
		(property "Tolerance" "TOL*"
			(at 0 4.861306 90)
			(unlocked yes)
			(layer "Cmts.User")
			(hide yes)
			(effects
				(font
					(size 0.7874 0.5842)
					(thickness 0.127)
				)
				(justify mirror)
			)
		)
		(duplicate_pad_numbers_are_jumpers no)
		(fp_line
			(start 0.970026 -0.4699)
			(end -0.970026 -0.4699)
			(stroke
				(width 0.1)
				(type default)
			)
			(layer "B.SilkS")
		)
		(fp_line
			(start -0.970026 -0.4699)
			(end -0.970026 0.4699)
			(stroke
				(width 0.1)
				(type default)
			)
			(layer "B.SilkS")
		)
		(fp_line
			(start 0.970026 0.4699)
			(end 0.970026 -0.4699)
			(stroke
				(width 0.1)
				(type default)
			)
			(layer "B.SilkS")
		)
		(fp_line
			(start -0.970026 0.4699)
			(end 0.970026 0.4699)
			(stroke
				(width 0.1)
				(type default)
			)
			(layer "B.SilkS")
		)
		(fp_poly
			(pts
				(xy 0.970026 0.4699) (xy -0.970026 0.4699) (xy -0.970026 -0.4699) (xy 0.970026 -0.4699)
			)
			(stroke
				(width 0)
				(type default)
			)
			(fill no)
			(layer "B.CrtYd")
		)
		(fp_line
			(start 0.508 -0.3048)
			(end -0.508 -0.3048)
			(stroke
				(width 0.1)
				(type default)
			)
			(layer "B.Fab")
		)
		(fp_line
			(start -0.508 -0.3048)
			(end -0.508 0.3048)
			(stroke
				(width 0.1)
				(type default)
			)
			(layer "B.Fab")
		)
		(fp_line
			(start 0.508 0.3048)
			(end 0.508 -0.3048)
			(stroke
				(width 0.1)
				(type default)
			)
			(layer "B.Fab")
		)
		(fp_line
			(start -0.508 0.3048)
			(end 0.508 0.3048)
			(stroke
				(width 0.1)
				(type default)
			)
			(layer "B.Fab")
		)
		(pad "1" smd circle
			(at 0.500126 0 270)
			(size 0.635 0.635)
			(layers "B.Cu" "B.Mask" "B.Paste")
			(net "XP1R0V_FPGA_VCCINT")
		)
		(pad "2" smd circle
			(at -0.500126 0 270)
			(size 0.635 0.635)
			(layers "B.Cu" "B.Mask" "B.Paste")
			(net "SG")
		)
	)
	(footprint ""
		(layer "B.Cu")
		(at 83.2358 -83.693 180)
		(property "Reference" "R153"
			(at 0.6858 5.67563 0)
			(unlocked yes)
			(layer "B.SilkS")
			(effects
				(font
					(size 0.7874 0.5842)
					(thickness 0.1524)
				)
				(justify mirror)
			)
		)
		(property "Value" "VAL*"
			(at -0.02032 2.13233 180)
			(unlocked yes)
			(layer "B.Fab")
			(hide yes)
			(effects
				(font
					(size 0.7874 0.5842)
					(thickness 0.1524)
				)
				(justify mirror)
			)
		)
		(property "Tolerance" "TOL*"
			(at -0.044704 3.05435 180)
			(unlocked yes)
			(layer "Cmts.User")
			(hide yes)
			(effects
				(font
					(size 0.7874 0.5842)
					(thickness 0.1524)
				)
				(justify mirror)
			)
		)
		(property "User Part Number" "PARTNUM*"
			(at -0.02032 4.024884 180)
			(unlocked yes)
			(layer "Cmts.User")
			(hide yes)
			(effects
				(font
					(size 0.7874 0.5842)
					(thickness 0.1524)
				)
				(justify mirror)
			)
		)
		(property "Device Type" "RESISTOR-G155-14701-01,4.7KOHMA"
			(at -0.008382 1.210564 180)
			(unlocked yes)
			(layer "B.Fab")
			(hide yes)
			(effects
				(font
					(size 0.7874 0.5842)
					(thickness 0.1524)
				)
				(justify mirror)
			)
		)
		(duplicate_pad_numbers_are_jumpers no)
		(fp_line
			(start 1.143 0.5588)
			(end -1.143 0.5588)
			(stroke
				(width 0.1)
				(type default)
			)
			(layer "B.SilkS")
		)
		(fp_line
			(start 1.143 -0.5588)
			(end 1.143 0.5588)
			(stroke
				(width 0.1)
				(type default)
			)
			(layer "B.SilkS")
		)
		(fp_line
			(start -1.143 0.5588)
			(end -1.143 -0.5588)
			(stroke
				(width 0.1)
				(type default)
			)
			(layer "B.SilkS")
		)
		(fp_line
			(start -1.143 -0.5588)
			(end 1.143 -0.5588)
			(stroke
				(width 0.1)
				(type default)
			)
			(layer "B.SilkS")
		)
		(fp_rect
			(start -1.143 0.5588)
			(end 1.143 -0.5588)
			(stroke
				(width 0)
				(type default)
			)
			(fill no)
			(layer "B.CrtYd")
		)
		(fp_line
			(start 0.508 0.3048)
			(end -0.508 0.3048)
			(stroke
				(width 0.1)
				(type default)
			)
			(layer "B.Fab")
		)
		(fp_line
			(start 0.508 -0.3048)
			(end 0.508 0.3048)
			(stroke
				(width 0.1)
				(type default)
			)
			(layer "B.Fab")
		)
		(fp_line
			(start -0.508 0.3048)
			(end -0.508 -0.3048)
			(stroke
				(width 0.1)
				(type default)
			)
			(layer "B.Fab")
		)
		(fp_line
			(start -0.508 -0.3048)
			(end 0.508 -0.3048)
			(stroke
				(width 0.1)
				(type default)
			)
			(layer "B.Fab")
		)
		(pad "1" smd rect
			(at 0.5334 0)
			(size 0.7112 0.6096)
			(layers "B.Cu" "B.Mask" "B.Paste")
			(net "SG")
		)
		(pad "2" smd rect
			(at -0.5334 0)
			(size 0.7112 0.6096)
			(layers "B.Cu" "B.Mask" "B.Paste")
			(net "UNNAMED_5_PCA9546APWTSSOP16_I_1")
		)
		(zone
			(layer "B.Cu")
			(hatch none 0.5)
			(connect_pads
				(clearance 0)
			)
			(min_thickness 0.25)
			(keepout
				(tracks allowed)
				(vias not_allowed)
				(pads allowed)
				(copperpour not_allowed)
				(footprints allowed)
			)
			(placement
				(enabled no)
				(sheetname "")
			)
			(fill
				(thermal_gap 0.5)
				(thermal_bridge_width 0.5)
				(island_removal_mode 0)
			)
			(polygon
				(pts
					(xy 83.312 -83.9978) (xy 83.1596 -83.9978) (xy 83.1596 -83.3882) (xy 83.312 -83.3882)
				)
			)
		)
	)
)
